# T6G (Grand Teton) — schematic netlist excerpt (pin names and nets, part order shuffled) for the footprints in the layout excerpt that follows; sources: Cadence DE-HDL packaged netlist, KiCad conversion of 04192023_DAF0TMB3IC0_F0TG_MB_C_brd_V02_OCP.brd

C841  Q_CAP_DIFFBUS  DIFF BUS_0.22UF 6.3V 20% X6S  pkg C0201  page 64 : \1\ = P5E_CPU0_P2_TX_C_DP<14> ; \2\ = P5E_CPU0_P2_TX_DP<14>
PC1870  Q_CAP  0.1UF 25V 10% EMPTY  pkg 0402  page 190 : A = P3V3_AUX_EN ; B = GND
R4419  Q_RES  49.9 1% EMPTY  pkg 0402LF  page 234 : A = USB2_HOST_BMC_B_DP ; B = GND

(kicad_pcb
	(version 20260206)
	(generator "pcbnew")
	(generator_version "10.0")
	(general
		(thickness 1.6)
		(legacy_teardrops no)
	)
	(paper "A4")
	(title_block
		(title "04192023_DAF0TMB3IC0_F0TG_MB_C_brd_V02_OCP.brd")
		(comment 1 "Grand Teton / footprints 3750-3752 of 8354")
	)
	(layers
		(0 "F.Cu" signal "TOP")
		(4 "In1.Cu" signal "GND")
		(6 "In2.Cu" signal "IN1")
		(8 "In3.Cu" signal "GND1")
		(10 "In4.Cu" signal "IN2")
		(12 "In5.Cu" signal "GND2")
		(14 "In6.Cu" signal "IN3")
		(16 "In7.Cu" signal "GND3")
		(18 "In8.Cu" signal "VCC")
		(20 "In9.Cu" signal "VCC1")
		(22 "In10.Cu" signal "GND4")
		(24 "In11.Cu" signal "IN4")
		(26 "In12.Cu" signal "GND5")
		(28 "In13.Cu" signal "IN5")
		(30 "In14.Cu" signal "GND6")
		(32 "In15.Cu" signal "IN6")
		(34 "In16.Cu" signal "GND7")
		(2 "B.Cu" signal "BOTTOM")
		(9 "F.Adhes" user "F.Adhesive")
		(11 "B.Adhes" user "B.Adhesive")
		(13 "F.Paste" user "Package Geometry/Pastemask Top")
		(15 "B.Paste" user "Package Geometry/Pastemask Bottom")
		(5 "F.SilkS" user "Ref Des/Silkscreen Top")
		(7 "B.SilkS" user "Ref Des/Silkscreen Bottom")
		(1 "F.Mask" user "Board Geometry/Soldermask Top")
		(3 "B.Mask" user "Board Geometry/Soldermask Bottom")
		(17 "Dwgs.User" user "User.Drawings")
		(19 "Cmts.User" user "User.Comments")
		(21 "Eco1.User" user "User.Eco1")
		(23 "Eco2.User" user "User.Eco2")
		(25 "Edge.Cuts" user "Board Geometry/Outline")
		(27 "Margin" user)
		(31 "F.CrtYd" user "Package Geometry/Place Bound Top")
		(29 "B.CrtYd" user "Package Geometry/Place Bound Bottom")
		(35 "F.Fab" user "Ref Des/Assembly Top")
		(33 "B.Fab" user "Ref Des/Assembly Bottom")
	)
	(footprint ""
		(layer "F.Cu")
		(at 14.265402 -105.537762 90)
		(property "Reference" "R4419"
			(at 0 0 90)
			(layer "F.SilkS")
			(hide yes)
			(effects
				(font
					(size 1.27 1.27)
				)
			)
		)
		(property "Value" ""
			(at 0 0 90)
			(layer "F.Fab")
			(effects
				(font
					(size 1.27 1.27)
				)
			)
		)
		(duplicate_pad_numbers_are_jumpers no)
		(fp_line
			(start 0.7874 -0.4064)
			(end 0.7874 0.4064)
			(stroke
				(width 0.1524)
				(type default)
			)
			(layer "F.SilkS")
		)
		(fp_line
			(start -0.7874 -0.4064)
			(end 0.7874 -0.4064)
			(stroke
				(width 0.1524)
				(type default)
			)
			(layer "F.SilkS")
		)
		(fp_line
			(start 0.7874 0.4064)
			(end -0.7874 0.4064)
			(stroke
				(width 0.1524)
				(type default)
			)
			(layer "F.SilkS")
		)
		(fp_line
			(start -0.7874 0.4064)
			(end -0.7874 -0.4064)
			(stroke
				(width 0.1524)
				(type default)
			)
			(layer "F.SilkS")
		)
		(fp_line
			(start -0.12065 -0.305054)
			(end -0.12065 -0.2794)
			(stroke
				(width 0.1)
				(type default)
			)
			(layer "F.Fab")
		)
		(fp_line
			(start -0.67945 -0.305054)
			(end -0.12065 -0.305054)
			(stroke
				(width 0.1)
				(type default)
			)
			(layer "F.Fab")
		)
		(fp_line
			(start 0.67945 -0.3048)
			(end 0.67945 0.3048)
			(stroke
				(width 0.1)
				(type default)
			)
			(layer "F.Fab")
		)
		(fp_line
			(start 0.12065 -0.3048)
			(end 0.67945 -0.3048)
			(stroke
				(width 0.1)
				(type default)
			)
			(layer "F.Fab")
		)
		(fp_line
			(start 0.12065 -0.2794)
			(end 0.12065 -0.3048)
			(stroke
				(width 0.1)
				(type default)
			)
			(layer "F.Fab")
		)
		(fp_line
			(start -0.12065 -0.2794)
			(end 0.12065 -0.2794)
			(stroke
				(width 0.1)
				(type default)
			)
			(layer "F.Fab")
		)
		(fp_line
			(start 0.120396 0.2794)
			(end -0.12065 0.2794)
			(stroke
				(width 0.1)
				(type default)
			)
			(layer "F.Fab")
		)
		(fp_line
			(start -0.12065 0.2794)
			(end -0.12065 0.3048)
			(stroke
				(width 0.1)
				(type default)
			)
			(layer "F.Fab")
		)
		(fp_line
			(start 0.67945 0.3048)
			(end 0.120396 0.3048)
			(stroke
				(width 0.1)
				(type default)
			)
			(layer "F.Fab")
		)
		(fp_line
			(start 0.120396 0.3048)
			(end 0.120396 0.2794)
			(stroke
				(width 0.1)
				(type default)
			)
			(layer "F.Fab")
		)
		(fp_line
			(start -0.12065 0.3048)
			(end -0.67945 0.3048)
			(stroke
				(width 0.1)
				(type default)
			)
			(layer "F.Fab")
		)
		(fp_line
			(start -0.67945 0.3048)
			(end -0.67945 -0.305054)
			(stroke
				(width 0.1)
				(type default)
			)
			(layer "F.Fab")
		)
		(pad "1" smd circle
			(at -0.40005 0 90)
			(size 0 0)
			(layers "F.Cu" "F.Mask" "F.Paste")
			(net "USB2_HOST_BMC_B_DP")
		)
		(pad "2" smd circle
			(at 0.40005 0 90)
			(size 0 0)
			(layers "F.Cu" "F.Mask" "F.Paste")
			(net "GND")
		)
	)
	(footprint ""
		(layer "F.Cu")
		(at 452.13905 -47.475394 180)
		(property "Reference" "PC1870"
			(at 0 0 180)
			(layer "F.SilkS")
			(hide yes)
			(effects
				(font
					(size 1.27 1.27)
				)
			)
		)
		(property "Value" ""
			(at 0 0 180)
			(layer "F.Fab")
			(effects
				(font
					(size 1.27 1.27)
				)
			)
		)
		(duplicate_pad_numbers_are_jumpers no)
		(fp_line
			(start 0.7874 0.4064)
			(end -0.7874 0.4064)
			(stroke
				(width 0.1524)
				(type default)
			)
			(layer "F.SilkS")
		)
		(fp_line
			(start 0.7874 -0.4064)
			(end 0.7874 0.4064)
			(stroke
				(width 0.1524)
				(type default)
			)
			(layer "F.SilkS")
		)
		(fp_line
			(start -0.7874 0.4064)
			(end -0.7874 -0.4064)
			(stroke
				(width 0.1524)
				(type default)
			)
			(layer "F.SilkS")
		)
		(fp_line
			(start -0.7874 -0.4064)
			(end 0.7874 -0.4064)
			(stroke
				(width 0.1524)
				(type default)
			)
			(layer "F.SilkS")
		)
		(fp_line
			(start 0.67945 0.3048)
			(end 0.120396 0.3048)
			(stroke
				(width 0.1)
				(type default)
			)
			(layer "F.Fab")
		)
		(fp_line
			(start 0.67945 -0.3048)
			(end 0.67945 0.3048)
			(stroke
				(width 0.1)
				(type default)
			)
			(layer "F.Fab")
		)
		(fp_line
			(start 0.12065 -0.2794)
			(end 0.12065 -0.3048)
			(stroke
				(width 0.1)
				(type default)
			)
			(layer "F.Fab")
		)
		(fp_line
			(start 0.12065 -0.3048)
			(end 0.67945 -0.3048)
			(stroke
				(width 0.1)
				(type default)
			)
			(layer "F.Fab")
		)
		(fp_line
			(start 0.120396 0.3048)
			(end 0.120396 0.2794)
			(stroke
				(width 0.1)
				(type default)
			)
			(layer "F.Fab")
		)
		(fp_line
			(start 0.120396 0.2794)
			(end -0.12065 0.2794)
			(stroke
				(width 0.1)
				(type default)
			)
			(layer "F.Fab")
		)
		(fp_line
			(start -0.12065 0.3048)
			(end -0.67945 0.3048)
			(stroke
				(width 0.1)
				(type default)
			)
			(layer "F.Fab")
		)
		(fp_line
			(start -0.12065 0.2794)
			(end -0.12065 0.3048)
			(stroke
				(width 0.1)
				(type default)
			)
			(layer "F.Fab")
		)
		(fp_line
			(start -0.12065 -0.2794)
			(end 0.12065 -0.2794)
			(stroke
				(width 0.1)
				(type default)
			)
			(layer "F.Fab")
		)
		(fp_line
			(start -0.12065 -0.305054)
			(end -0.12065 -0.2794)
			(stroke
				(width 0.1)
				(type default)
			)
			(layer "F.Fab")
		)
		(fp_line
			(start -0.67945 0.3048)
			(end -0.67945 -0.305054)
			(stroke
				(width 0.1)
				(type default)
			)
			(layer "F.Fab")
		)
		(fp_line
			(start -0.67945 -0.305054)
			(end -0.12065 -0.305054)
			(stroke
				(width 0.1)
				(type default)
			)
			(layer "F.Fab")
		)
		(pad "1" smd circle
			(at -0.40005 0 180)
			(size 0 0)
			(layers "F.Cu" "F.Mask" "F.Paste")
			(net "P3V3_AUX_EN")
		)
		(pad "2" smd circle
			(at 0.40005 0 180)
			(size 0 0)
			(layers "F.Cu" "F.Mask" "F.Paste")
			(net "GND")
		)
	)
	(footprint ""
		(layer "F.Cu")
		(at 425.36872 -384.449828)
		(property "Reference" "C841"
			(at 0 0 0)
			(layer "F.SilkS")
			(hide yes)
			(effects
				(font
					(size 1.27 1.27)
				)
			)
		)
		(property "Value" ""
			(at 0 0 0)
			(layer "F.Fab")
			(effects
				(font
					(size 1.27 1.27)
				)
			)
		)
		(duplicate_pad_numbers_are_jumpers no)
		(fp_line
			(start -0.299974 -0.150114)
			(end 0.299974 -0.150114)
			(stroke
				(width 0.1)
				(type default)
			)
			(layer "F.Fab")
		)
		(fp_line
			(start -0.299974 0.150114)
			(end -0.299974 -0.150114)
			(stroke
				(width 0.1)
				(type default)
			)
			(layer "F.Fab")
		)
		(fp_line
			(start 0.299974 -0.150114)
			(end 0.299974 0.150114)
			(stroke
				(width 0.1)
				(type default)
			)
			(layer "F.Fab")
		)
		(fp_line
			(start 0.299974 0.150114)
			(end -0.299974 0.150114)
			(stroke
				(width 0.1)
				(type default)
			)
			(layer "F.Fab")
		)
		(pad "1" smd rect
			(at -0.2667 0)
			(size 0.3048 0.381)
			(layers "F.Cu" "F.Mask" "F.Paste")
			(net "P5E_CPU0_P2_TX_C_DP<14>")
		)
		(pad "2" smd rect
			(at 0.2667 0)
			(size 0.3048 0.381)
			(layers "F.Cu" "F.Mask" "F.Paste")
			(net "P5E_CPU0_P2_TX_DP<14>")
		)
	)
)
